# S9S_MB_2U (Grand Teton) — schematic netlist excerpt (pin names and nets, part order shuffled) for the footprints in the layout excerpt that follows; sources: Cadence DE-HDL packaged netlist, KiCad conversion of 03242023_DA0F0TMBIJ0_F0T_Motherboard_J_brd_V01_OCP.brd

J112  CONN160_10131762101LF  CONN160_10131762-101LF IO  pkg HSD_F160D8_P2W1-2_RDH  page 143
  A1  = RST_PERST_2_SWB_BUF_N
  A2  = GND
  A3  = HGX_DETECT_N_ISO
  A4  = GND
  A5  = RST_PERST_1_SWB_BUF_N
  A6  = GND
  A7  = PRSNT_SWB_N
  A8  = GND
  B1  = GND
  B2  = P5E_CPU1_PE0_RX_DN<14>
  B3  = GND
  B4  = P5E_CPU1_PE0_RX_DN<12>
  B5  = GND
  B6  = P5E_CPU1_PE0_RX_DN<10>
  B7  = GND
  B8  = P5E_CPU1_PE0_RX_DN<8>
  C1  = P5E_CPU1_PE0_RX_DN<15>
  C2  = P5E_CPU1_PE0_RX_DP<14>
  C3  = P5E_CPU1_PE0_RX_DN<13>
  C4  = P5E_CPU1_PE0_RX_DP<12>
  C5  = P5E_CPU1_PE0_RX_DP<11>
  C6  = P5E_CPU1_PE0_RX_DP<10>
  C7  = P5E_CPU1_PE0_RX_DN<9>
  C8  = P5E_CPU1_PE0_RX_DP<8>
  D1  = P5E_CPU1_PE0_RX_DP<15>
  D2  = GND
  D3  = P5E_CPU1_PE0_RX_DP<13>
  D4  = GND
  D5  = P5E_CPU1_PE0_RX_DN<11>
  D6  = GND
  D7  = P5E_CPU1_PE0_RX_DP<9>
  D8  = GND
  E1  = GND
  E2  = P5E_CPU1_PE4_RX_DP<1>
  E3  = GND
  E4  = P5E_CPU1_PE4_RX_DP<3>
  E5  = GND
  E6  = P5E_CPU1_PE4_RX_DP<5>
  E7  = GND
  E8  = P5E_CPU1_PE4_RX_DP<7>
  F1  = P5E_CPU1_PE4_RX_DN<0>
  F2  = P5E_CPU1_PE4_RX_DN<1>
  F3  = P5E_CPU1_PE4_RX_DN<2>
  F4  = P5E_CPU1_PE4_RX_DN<3>
  F5  = P5E_CPU1_PE4_RX_DN<4>
  F6  = P5E_CPU1_PE4_RX_DN<5>
  F7  = P5E_CPU1_PE4_RX_DN<6>
  F8  = P5E_CPU1_PE4_RX_DN<7>
  G1  = P5E_CPU1_PE4_RX_DP<0>
  G2  = GND
  G3  = P5E_CPU1_PE4_RX_DP<2>
  G4  = GND
  G5  = P5E_CPU1_PE4_RX_DP<4>
  G6  = GND
  G7  = P5E_CPU1_PE4_RX_DP<6>
  G8  = GND
  H1  = GND
  H2  = P5E_CPU1_PE0_TX_C_DN<14>
  H3  = GND
  H4  = P5E_CPU1_PE0_TX_C_DN<12>
  H5  = GND
  H6  = P5E_CPU1_PE0_TX_C_DN<10>
  H7  = GND
  H8  = P5E_CPU1_PE0_TX_C_DN<8>
  I1  = P5E_CPU1_PE0_TX_C_DN<15>
  I2  = P5E_CPU1_PE0_TX_C_DP<14>
  I3  = P5E_CPU1_PE0_TX_C_DN<13>
  I4  = P5E_CPU1_PE0_TX_C_DP<12>
  I5  = P5E_CPU1_PE0_TX_C_DN<11>
  I6  = P5E_CPU1_PE0_TX_C_DP<10>
  I7  = P5E_CPU1_PE0_TX_C_DN<9>
  I8  = P5E_CPU1_PE0_TX_C_DP<8>
  J1  = P5E_CPU1_PE0_TX_C_DP<15>
  J2  = GND
  J3  = P5E_CPU1_PE0_TX_C_DP<13>
  J4  = GND
  J5  = P5E_CPU1_PE0_TX_C_DP<11>
  J6  = GND
  J7  = P5E_CPU1_PE0_TX_C_DP<9>
  J8  = GND
  K1  = GND
  K2  = P5E_CPU1_PE4_TX_C_DP<1>
  K3  = GND
  K4  = P5E_CPU1_PE4_TX_C_DN<3>
  K5  = GND
  K6  = P5E_CPU1_PE4_TX_C_DN<5>
  K7  = GND
  K8  = P5E_CPU1_PE4_TX_C_DN<7>
  L1  = P5E_CPU1_PE4_TX_C_DN<0>
  L2  = P5E_CPU1_PE4_TX_C_DN<1>
  L3  = P5E_CPU1_PE4_TX_C_DN<2>
  L4  = P5E_CPU1_PE4_TX_C_DP<3>
  L5  = P5E_CPU1_PE4_TX_C_DN<4>
  L6  = P5E_CPU1_PE4_TX_C_DP<5>
  L7  = P5E_CPU1_PE4_TX_C_DN<6>
  L8  = P5E_CPU1_PE4_TX_C_DP<7>
  M1  = P5E_CPU1_PE4_TX_C_DP<0>
  M2  = GND
  M3  = P5E_CPU1_PE4_TX_C_DP<2>
  M4  = GND
  M5  = P5E_CPU1_PE4_TX_C_DP<4>
  M6  = GND
  M7  = P5E_CPU1_PE4_TX_C_DP<6>
  M8  = GND
  N1  = GND
  N2  = NC_J112_N2
  N3  = GND
  N4  = CLK_100M_GPU_1_DN
  N5  = GND
  N6  = P2E_MB_BMC_RX_DN<0>
  N7  = GND
  N8  = P3E_PCH_NVS_RX_DN<0>
  O1  = CLK_100M_GPU_2_DN
  O2  = NC_J112_O2
  O3  = CLK_100M_SWB_DN
  O4  = CLK_100M_GPU_1_DP
  O5  = NC_J112_O5
  O6  = P2E_MB_BMC_RX_DP<0>
  O7  = P3E_PCH_NVS_RX_DN<1>
  O8  = P3E_PCH_NVS_RX_DP<0>
  P1  = CLK_100M_GPU_2_DP
  P2  = GND
  P3  = CLK_100M_SWB_DP
  P4  = GND
  P5  = NC_J112_P5
  P6  = GND
  P7  = P3E_PCH_NVS_RX_DP<1>
  P8  = GND
  Q1  = GND
  Q2  = CLK_100M_GPU_FPGA_DN
  Q3  = GND
  Q4  = SMB_1_BMC_GPU_BUF_SCL
  Q5  = GND
  Q6  = P2E_MB_BMC_TX_BUF_C_DN<0>
  Q7  = GND
  Q8  = P3E_PCH_NVS_TX_C_DN<0>
  R1  = USB2_HUB_BUF_SWB_DN
  R2  = CLK_100M_GPU_FPGA_DP
  R3  = SMB_2_BMC_GPU_BUF_SCL
  R4  = SMB_1_BMC_GPU_BUF_SDA
  R5  = NC_J112_R5
  R6  = P2E_MB_BMC_TX_BUF_C_DP<0>
  R7  = P3E_PCH_NVS_TX_C_DN<1>
  R8  = P3E_PCH_NVS_TX_C_DP<0>
  S1  = USB2_HUB_BUF_SWB_DP
  S2  = GND
  S3  = SMB_2_BMC_GPU_BUF_SDA
  S4  = GND
  S5  = NC_J112_S5
  S6  = GND
  S7  = P3E_PCH_NVS_TX_C_DP<1>
  S8  = GND
  T1  = GND
  T2  = GPU_FPGA_READY
  T3  = GND
  T4  = GPU_NVS_PWR_BRAKE_N_BUF
  T5  = GND
  T6  = GPU_FPGA_THERM_OVERT_N
  T7  = GND
  T8  = RST_PERST_0_SWB_BUF_N

(kicad_pcb
	(version 20260206)
	(generator "pcbnew")
	(generator_version "10.0")
	(general
		(thickness 1.6)
		(legacy_teardrops no)
	)
	(paper "A4")
	(title_block
		(title "03242023_DA0F0TMBIJ0_F0T_Motherboard_J_brd_V01_OCP.brd")
		(comment 1 "Grand Teton / footprint 2126 of 6105 (J112), pads 1-31 of 90")
	)
	(layers
		(0 "F.Cu" signal "TOP")
		(4 "In1.Cu" signal "GND")
		(6 "In2.Cu" signal "IN1")
		(8 "In3.Cu" signal "GND1")
		(10 "In4.Cu" signal "IN2")
		(12 "In5.Cu" signal "GND2")
		(14 "In6.Cu" signal "IN3")
		(16 "In7.Cu" signal "GND3")
		(18 "In8.Cu" signal "VCC")
		(20 "In9.Cu" signal "VCC1")
		(22 "In10.Cu" signal "GND4")
		(24 "In11.Cu" signal "IN4")
		(26 "In12.Cu" signal "GND5")
		(28 "In13.Cu" signal "IN5")
		(30 "In14.Cu" signal "GND6")
		(32 "In15.Cu" signal "IN6")
		(34 "In16.Cu" signal "GND7")
		(2 "B.Cu" signal "BOTTOM")
		(9 "F.Adhes" user "F.Adhesive")
		(11 "B.Adhes" user "B.Adhesive")
		(13 "F.Paste" user "Package Geometry/Pastemask Top")
		(15 "B.Paste" user "Package Geometry/Pastemask Bottom")
		(5 "F.SilkS" user "Ref Des/Silkscreen Top")
		(7 "B.SilkS" user "Ref Des/Silkscreen Bottom")
		(1 "F.Mask" user "Board Geometry/Soldermask Top")
		(3 "B.Mask" user "Board Geometry/Soldermask Bottom")
		(17 "Dwgs.User" user "User.Drawings")
		(19 "Cmts.User" user "User.Comments")
		(21 "Eco1.User" user "User.Eco1")
		(23 "Eco2.User" user "User.Eco2")
		(25 "Edge.Cuts" user "Board Geometry/Outline")
		(27 "Margin" user)
		(31 "F.CrtYd" user "Package Geometry/Place Bound Top")
		(29 "B.CrtYd" user "Package Geometry/Place Bound Bottom")
		(35 "F.Fab" user "Ref Des/Assembly Top")
		(33 "B.Fab" user "Ref Des/Assembly Bottom")
	)
	(footprint ""
		(layer "F.Cu")
		(at 58.650124 -440.489848)
		(property "Reference" "J112"
			(at -7.9883 9.742932 0)
			(unlocked yes)
			(layer "F.SilkS")
			(effects
				(font
					(size 0.7874 0.5842)
					(thickness 0.1524)
				)
				(justify left)
			)
		)
		(property "Value" ""
			(at 0 0 0)
			(layer "F.Fab")
			(effects
				(font
					(size 1.27 1.27)
				)
			)
		)
		(duplicate_pad_numbers_are_jumpers no)
		(pad "A1" thru_hole rect
			(at 0 0 180)
			(size 0.766318 0.766318)
			(drill 0.359918)
			(layers "*.Cu" "*.Mask")
			(remove_unused_layers no)
			(net "RST_PERST_2_SWB_BUF_N")
			(clearance 0.0508)
			(thermal_gap 0.0508)
			(padstack
				(mode front_inner_back)
				(layer "Inner"
					(shape circle)
					(size 0.766318 0.766318)
					(clearance 0.0508)
				)
				(layer "B.Cu"
					(shape rect)
					(size 0.766318 0.766318)
					(clearance 0.0508)
				)
			)
		)
		(pad "A2" thru_hole circle
			(at 1.999996 0.199898 180)
			(size 0.906272 0.906272)
			(drill 0.499872)
			(layers "*.Cu" "*.Mask")
			(remove_unused_layers no)
			(net "GND")
			(clearance 0.0508)
			(thermal_gap 0.0508)
		)
		(pad "A3" thru_hole circle
			(at 3.999992 0 180)
			(size 0.766318 0.766318)
			(drill 0.359918)
			(layers "*.Cu" "*.Mask")
			(remove_unused_layers no)
			(net "HGX_DETECT_N_ISO")
			(clearance 0.0508)
			(thermal_gap 0.0508)
		)
		(pad "A4" thru_hole circle
			(at 5.999988 0.199898 180)
			(size 0.906272 0.906272)
			(drill 0.499872)
			(layers "*.Cu" "*.Mask")
			(remove_unused_layers no)
			(net "GND")
			(clearance 0.0508)
			(thermal_gap 0.0508)
		)
		(pad "A5" thru_hole circle
			(at 7.999984 0 180)
			(size 0.766318 0.766318)
			(drill 0.359918)
			(layers "*.Cu" "*.Mask")
			(remove_unused_layers no)
			(net "RST_PERST_1_SWB_BUF_N")
			(clearance 0.0508)
			(thermal_gap 0.0508)
		)
		(pad "A6" thru_hole circle
			(at 9.99998 0.199898 180)
			(size 0.906272 0.906272)
			(drill 0.499872)
			(layers "*.Cu" "*.Mask")
			(remove_unused_layers no)
			(net "GND")
			(clearance 0.0508)
			(thermal_gap 0.0508)
		)
		(pad "A7" thru_hole circle
			(at 11.999976 0 180)
			(size 0.766318 0.766318)
			(drill 0.359918)
			(layers "*.Cu" "*.Mask")
			(remove_unused_layers no)
			(net "PRSNT_SWB_N")
			(clearance 0.0508)
			(thermal_gap 0.0508)
		)
		(pad "A8" thru_hole circle
			(at 13.999972 0.199898 180)
			(size 0.906272 0.906272)
			(drill 0.499872)
			(layers "*.Cu" "*.Mask")
			(remove_unused_layers no)
			(net "GND")
			(clearance 0.0508)
			(thermal_gap 0.0508)
		)
		(pad "B1" thru_hole circle
			(at 0 1.199896 180)
			(size 0.906272 0.906272)
			(drill 0.499872)
			(layers "*.Cu" "*.Mask")
			(remove_unused_layers no)
			(net "GND")
			(clearance 0.0508)
			(thermal_gap 0.0508)
		)
		(pad "B3" thru_hole circle
			(at 3.999992 1.199896 180)
			(size 0.906272 0.906272)
			(drill 0.499872)
			(layers "*.Cu" "*.Mask")
			(remove_unused_layers no)
			(net "GND")
			(clearance 0.0508)
			(thermal_gap 0.0508)
		)
		(pad "B5" thru_hole circle
			(at 7.999984 1.199896 180)
			(size 0.906272 0.906272)
			(drill 0.499872)
			(layers "*.Cu" "*.Mask")
			(remove_unused_layers no)
			(net "GND")
			(clearance 0.0508)
			(thermal_gap 0.0508)
		)
		(pad "B7" thru_hole circle
			(at 11.999976 1.199896 180)
			(size 0.906272 0.906272)
			(drill 0.499872)
			(layers "*.Cu" "*.Mask")
			(remove_unused_layers no)
			(net "GND")
			(clearance 0.0508)
			(thermal_gap 0.0508)
		)
		(pad "D2" thru_hole circle
			(at 1.999996 3.800094 180)
			(size 0.906272 0.906272)
			(drill 0.499872)
			(layers "*.Cu" "*.Mask")
			(remove_unused_layers no)
			(net "GND")
			(clearance 0.0508)
			(thermal_gap 0.0508)
		)
		(pad "D4" thru_hole circle
			(at 5.999988 3.800094 180)
			(size 0.906272 0.906272)
			(drill 0.499872)
			(layers "*.Cu" "*.Mask")
			(remove_unused_layers no)
			(net "GND")
			(clearance 0.0508)
			(thermal_gap 0.0508)
		)
		(pad "D6" thru_hole circle
			(at 9.99998 3.800094 180)
			(size 0.906272 0.906272)
			(drill 0.499872)
			(layers "*.Cu" "*.Mask")
			(remove_unused_layers no)
			(net "GND")
			(clearance 0.0508)
			(thermal_gap 0.0508)
		)
		(pad "D8" thru_hole circle
			(at 13.999972 3.800094 180)
			(size 0.906272 0.906272)
			(drill 0.499872)
			(layers "*.Cu" "*.Mask")
			(remove_unused_layers no)
			(net "GND")
			(clearance 0.0508)
			(thermal_gap 0.0508)
		)
		(pad "E1" thru_hole circle
			(at 0 4.800092 180)
			(size 0.906272 0.906272)
			(drill 0.499872)
			(layers "*.Cu" "*.Mask")
			(remove_unused_layers no)
			(net "GND")
			(clearance 0.0508)
			(thermal_gap 0.0508)
		)
		(pad "E3" thru_hole circle
			(at 3.999992 4.800092 180)
			(size 0.906272 0.906272)
			(drill 0.499872)
			(layers "*.Cu" "*.Mask")
			(remove_unused_layers no)
			(net "GND")
			(clearance 0.0508)
			(thermal_gap 0.0508)
		)
		(pad "E5" thru_hole circle
			(at 7.999984 4.800092 180)
			(size 0.906272 0.906272)
			(drill 0.499872)
			(layers "*.Cu" "*.Mask")
			(remove_unused_layers no)
			(net "GND")
			(clearance 0.0508)
			(thermal_gap 0.0508)
		)
		(pad "E7" thru_hole circle
			(at 11.999976 4.800092 180)
			(size 0.906272 0.906272)
			(drill 0.499872)
			(layers "*.Cu" "*.Mask")
			(remove_unused_layers no)
			(net "GND")
			(clearance 0.0508)
			(thermal_gap 0.0508)
		)
		(pad "G2" thru_hole circle
			(at 1.999996 7.400036 180)
			(size 0.906272 0.906272)
			(drill 0.499872)
			(layers "*.Cu" "*.Mask")
			(remove_unused_layers no)
			(net "GND")
			(clearance 0.0508)
			(thermal_gap 0.0508)
		)
		(pad "G4" thru_hole circle
			(at 5.999988 7.400036 180)
			(size 0.906272 0.906272)
			(drill 0.499872)
			(layers "*.Cu" "*.Mask")
			(remove_unused_layers no)
			(net "GND")
			(clearance 0.0508)
			(thermal_gap 0.0508)
		)
		(pad "G6" thru_hole circle
			(at 9.99998 7.400036 180)
			(size 0.906272 0.906272)
			(drill 0.499872)
			(layers "*.Cu" "*.Mask")
			(remove_unused_layers no)
			(net "GND")
			(clearance 0.0508)
			(thermal_gap 0.0508)
		)
		(pad "G8" thru_hole circle
			(at 13.999972 7.400036 180)
			(size 0.906272 0.906272)
			(drill 0.499872)
			(layers "*.Cu" "*.Mask")
			(remove_unused_layers no)
			(net "GND")
			(clearance 0.0508)
			(thermal_gap 0.0508)
		)
		(pad "H1" thru_hole circle
			(at 0 8.400034 180)
			(size 0.906272 0.906272)
			(drill 0.499872)
			(layers "*.Cu" "*.Mask")
			(remove_unused_layers no)
			(net "GND")
			(clearance 0.0508)
			(thermal_gap 0.0508)
		)
		(pad "H3" thru_hole circle
			(at 3.999992 8.400034 180)
			(size 0.906272 0.906272)
			(drill 0.499872)
			(layers "*.Cu" "*.Mask")
			(remove_unused_layers no)
			(net "GND")
			(clearance 0.0508)
			(thermal_gap 0.0508)
		)
		(pad "H5" thru_hole circle
			(at 7.999984 8.400034 180)
			(size 0.906272 0.906272)
			(drill 0.499872)
			(layers "*.Cu" "*.Mask")
			(remove_unused_layers no)
			(net "GND")
			(clearance 0.0508)
			(thermal_gap 0.0508)
		)
		(pad "H7" thru_hole circle
			(at 11.999976 8.400034 180)
			(size 0.906272 0.906272)
			(drill 0.499872)
			(layers "*.Cu" "*.Mask")
			(remove_unused_layers no)
			(net "GND")
			(clearance 0.0508)
			(thermal_gap 0.0508)
		)
		(pad "J2" thru_hole circle
			(at 1.999996 10.999978 180)
			(size 0.906272 0.906272)
			(drill 0.499872)
			(layers "*.Cu" "*.Mask")
			(remove_unused_layers no)
			(net "GND")
			(clearance 0.0508)
			(thermal_gap 0.0508)
		)
		(pad "J4" thru_hole circle
			(at 5.999988 10.999978 180)
			(size 0.906272 0.906272)
			(drill 0.499872)
			(layers "*.Cu" "*.Mask")
			(remove_unused_layers no)
			(net "GND")
			(clearance 0.0508)
			(thermal_gap 0.0508)
		)
		(pad "J6" thru_hole circle
			(at 9.99998 10.999978 180)
			(size 0.906272 0.906272)
			(drill 0.499872)
			(layers "*.Cu" "*.Mask")
			(remove_unused_layers no)
			(net "GND")
			(clearance 0.0508)
			(thermal_gap 0.0508)
		)
	)
)
